# BASEBOARD_FAB2 (Tioga Pass) — schematic netlist excerpt (pin names and nets, part order shuffled) for the footprints in the layout excerpt that follows; sources: Cadence DE-HDL packaged netlist, KiCad conversion of Wiwynn_Tioga_Pass_MB.brd

R1L17  RES  150.0 1% CHIP  pkg 0402  page 111 : A = XDP_CPU_PWR_DEBUG_N ; B = PVCCIO_CPU0

L30W2  CHOKE_4PIN  67 OHM EMPTY  pkg SM_B  page 253
  \1\  = USB3_P01_C_TXP
  \2\  = USB3_P01_FB_TXP
  \3\  = USB3_P01_FB_TXN
  \4\  = USB3_P01_C_TXN

(kicad_pcb
	(version 20260206)
	(generator "pcbnew")
	(generator_version "10.0")
	(general
		(thickness 1.6)
		(legacy_teardrops no)
	)
	(paper "A4")
	(title_block
		(title "Wiwynn_Tioga_Pass_MB.brd")
		(comment 1 "Tioga Pass / footprints 4014-4015 of 4770")
	)
	(layers
		(0 "F.Cu" signal "TOP")
		(4 "In1.Cu" signal "L2GND")
		(6 "In2.Cu" signal "L3")
		(8 "In3.Cu" signal "L4GND")
		(10 "In4.Cu" signal "L5")
		(12 "In5.Cu" signal "L6GND")
		(14 "In6.Cu" signal "L7VCC")
		(16 "In7.Cu" signal "L8VCC")
		(18 "In8.Cu" signal "L9GND")
		(20 "In9.Cu" signal "L10")
		(22 "In10.Cu" signal "L11GND")
		(24 "In11.Cu" signal "L12")
		(26 "In12.Cu" signal "L13GND")
		(2 "B.Cu" signal "BOTTOM")
		(9 "F.Adhes" user "F.Adhesive")
		(11 "B.Adhes" user "B.Adhesive")
		(13 "F.Paste" user "Package Geometry/Pastemask Top")
		(15 "B.Paste" user "Package Geometry/Pastemask Bottom")
		(5 "F.SilkS" user "Ref Des/Silkscreen Top")
		(7 "B.SilkS" user "Ref Des/Silkscreen Bottom")
		(1 "F.Mask" user "Board Geometry/Soldermask Top")
		(3 "B.Mask" user "Board Geometry/Soldermask Bottom")
		(17 "Dwgs.User" user "User.Drawings")
		(19 "Cmts.User" user "User.Comments")
		(21 "Eco1.User" user "User.Eco1")
		(23 "Eco2.User" user "User.Eco2")
		(25 "Edge.Cuts" user "Board Geometry/Outline")
		(27 "Margin" user)
		(31 "F.CrtYd" user "Package Geometry/Place Bound Top")
		(29 "B.CrtYd" user "Package Geometry/Place Bound Bottom")
		(35 "F.Fab" user "Ref Des/Assembly Top")
		(33 "B.Fab" user "Ref Des/Assembly Bottom")
	)
	(footprint ""
		(layer "B.Cu")
		(at 487.62412 -60.016644 180)
		(property "Reference" "L30W2"
			(at -0.127 -1.07188 180)
			(unlocked yes)
			(layer "B.SilkS")
			(effects
				(font
					(size 0.4064 0.254)
					(thickness 0.1524)
				)
				(justify left mirror)
			)
		)
		(property "Value" ""
			(at 0 0 0)
			(layer "B.Fab")
			(effects
				(font
					(size 1.27 1.27)
				)
				(justify mirror)
			)
		)
		(duplicate_pad_numbers_are_jumpers no)
		(fp_rect
			(start 0.08382 1.09982)
			(end -2.11582 -0.29972)
			(stroke
				(width 0)
				(type default)
			)
			(fill no)
			(layer "B.CrtYd")
		)
		(fp_line
			(start 0.08382 1.09982)
			(end 0.08382 -0.29972)
			(stroke
				(width 0.1)
				(type default)
			)
			(layer "B.Fab")
		)
		(fp_line
			(start 0.08382 -0.29972)
			(end -2.11582 -0.29972)
			(stroke
				(width 0.1)
				(type default)
			)
			(layer "B.Fab")
		)
		(fp_line
			(start -2.11582 1.09982)
			(end 0.08382 1.09982)
			(stroke
				(width 0.1)
				(type default)
			)
			(layer "B.Fab")
		)
		(fp_line
			(start -2.11582 -0.29972)
			(end -2.11582 1.09982)
			(stroke
				(width 0.1)
				(type default)
			)
			(layer "B.Fab")
		)
		(pad "1" smd rect
			(at 0 0)
			(size 1.27 0.508)
			(layers "B.Cu" "B.Mask" "B.Paste")
			(net "USB3_P01_C_TXP")
		)
		(pad "2" smd rect
			(at -2.032 0)
			(size 1.27 0.508)
			(layers "B.Cu" "B.Mask" "B.Paste")
			(net "USB3_P01_FB_TXP")
		)
		(pad "3" smd rect
			(at -2.032 0.8001)
			(size 1.27 0.508)
			(layers "B.Cu" "B.Mask" "B.Paste")
			(net "USB3_P01_FB_TXN")
		)
		(pad "4" smd rect
			(at 0 0.8001)
			(size 1.27 0.508)
			(layers "B.Cu" "B.Mask" "B.Paste")
			(net "USB3_P01_C_TXN")
		)
		(zone
			(layer "B.Cu")
			(hatch none 0.5)
			(connect_pads
				(clearance 0)
			)
			(min_thickness 0.25)
			(keepout
				(tracks not_allowed)
				(vias allowed)
				(pads allowed)
				(copperpour not_allowed)
				(footprints allowed)
			)
			(placement
				(enabled no)
				(sheetname "")
			)
			(fill
				(thermal_gap 0.5)
				(thermal_bridge_width 0.5)
				(island_removal_mode 0)
			)
			(polygon
				(pts
					(xy 486.98912 -60.562744) (xy 486.98912 -60.270644) (xy 488.25912 -60.270644) (xy 488.25912 -60.562744)
				)
			)
		)
		(zone
			(layer "B.Cu")
			(hatch none 0.5)
			(connect_pads
				(clearance 0)
			)
			(min_thickness 0.25)
			(keepout
				(tracks not_allowed)
				(vias allowed)
				(pads allowed)
				(copperpour not_allowed)
				(footprints allowed)
			)
			(placement
				(enabled no)
				(sheetname "")
			)
			(fill
				(thermal_gap 0.5)
				(thermal_bridge_width 0.5)
				(island_removal_mode 0)
			)
			(polygon
				(pts
					(xy 488.25912 -61.070744) (xy 489.02112 -61.070744) (xy 489.02112 -59.762644) (xy 488.25912 -59.762644)
				)
			)
		)
		(zone
			(layer "B.Cu")
			(hatch none 0.5)
			(connect_pads
				(clearance 0)
			)
			(min_thickness 0.25)
			(keepout
				(tracks allowed)
				(vias not_allowed)
				(pads allowed)
				(copperpour not_allowed)
				(footprints allowed)
			)
			(placement
				(enabled no)
				(sheetname "")
			)
			(fill
				(thermal_gap 0.5)
				(thermal_bridge_width 0.5)
				(island_removal_mode 0)
			)
			(polygon
				(pts
					(xy 488.25912 -59.762644) (xy 488.25912 -61.070744) (xy 489.02112 -61.070744) (xy 489.02112 -59.762644)
				)
			)
		)
		(zone
			(layer "B.Cu")
			(hatch none 0.5)
			(connect_pads
				(clearance 0)
			)
			(min_thickness 0.25)
			(keepout
				(tracks not_allowed)
				(vias allowed)
				(pads allowed)
				(copperpour not_allowed)
				(footprints allowed)
			)
			(placement
				(enabled no)
				(sheetname "")
			)
			(fill
				(thermal_gap 0.5)
				(thermal_bridge_width 0.5)
				(island_removal_mode 0)
			)
			(polygon
				(pts
					(xy 489.02112 -60.562744) (xy 489.02112 -60.270644) (xy 490.29112 -60.270644) (xy 490.29112 -60.562744)
				)
			)
		)
	)
	(footprint ""
		(layer "B.Cu")
		(at 465.595208 -147.066254)
		(property "Reference" "R1L17"
			(at 0 0 0)
			(layer "B.SilkS")
			(hide yes)
			(effects
				(font
					(size 1.27 1.27)
				)
				(justify mirror)
			)
		)
		(property "Value" ""
			(at 0 0 0)
			(layer "B.Fab")
			(effects
				(font
					(size 1.27 1.27)
				)
				(justify mirror)
			)
		)
		(duplicate_pad_numbers_are_jumpers no)
		(fp_poly
			(pts
				(xy 0.2794 -0.1016) (xy -0.2794 -0.1016) (xy -0.2794 0.9906) (xy 0.2794 0.9906)
			)
			(stroke
				(width 0)
				(type default)
			)
			(fill no)
			(layer "B.CrtYd")
		)
		(fp_line
			(start -0.2794 -0.1016)
			(end 0.2794 -0.1016)
			(stroke
				(width 0.1)
				(type default)
			)
			(layer "B.Fab")
		)
		(fp_line
			(start -0.2794 0.9906)
			(end -0.2794 -0.1016)
			(stroke
				(width 0.1)
				(type default)
			)
			(layer "B.Fab")
		)
		(fp_line
			(start 0.2794 -0.1016)
			(end 0.2794 0.9906)
			(stroke
				(width 0.1)
				(type default)
			)
			(layer "B.Fab")
		)
		(fp_line
			(start 0.2794 0.9906)
			(end -0.2794 0.9906)
			(stroke
				(width 0.1)
				(type default)
			)
			(layer "B.Fab")
		)
		(pad "1" smd rect
			(at 0 0 180)
			(size 0.508 0.508)
			(layers "B.Cu" "B.Mask" "B.Paste")
			(net "XDP_CPU_PWR_DEBUG_N")
		)
		(pad "2" smd rect
			(at 0 0.889 180)
			(size 0.508 0.508)
			(layers "B.Cu" "B.Mask" "B.Paste")
			(net "PVCCIO_CPU0")
		)
		(zone
			(layer "B.Cu")
			(hatch none 0.5)
			(connect_pads
				(clearance 0)
			)
			(min_thickness 0.25)
			(keepout
				(tracks allowed)
				(vias not_allowed)
				(pads allowed)
				(copperpour not_allowed)
				(footprints allowed)
			)
			(placement
				(enabled no)
				(sheetname "")
			)
			(fill
				(thermal_gap 0.5)
				(thermal_bridge_width 0.5)
				(island_removal_mode 0)
			)
			(polygon
				(pts
					(xy 465.849208 -146.812254) (xy 465.341208 -146.812254) (xy 465.341208 -146.431254) (xy 465.849208 -146.431254)
				)
			)
		)
		(zone
			(layer "B.Cu")
			(hatch none 0.5)
			(connect_pads
				(clearance 0)
			)
			(min_thickness 0.25)
			(keepout
				(tracks not_allowed)
				(vias allowed)
				(pads allowed)
				(copperpour not_allowed)
				(footprints allowed)
			)
			(placement
				(enabled no)
				(sheetname "")
			)
			(fill
				(thermal_gap 0.5)
				(thermal_bridge_width 0.5)
				(island_removal_mode 0)
			)
			(polygon
				(pts
					(xy 465.849208 -146.431254) (xy 465.341208 -146.431254) (xy 465.341208 -146.812254) (xy 465.849208 -146.812254)
				)
			)
		)
	)
)
